(kicad_pcb
	(version 20260206)
	(generator "pcbnew")
	(generator_version "10.0")
	(general
		(thickness 1.6)
		(legacy_teardrops no)
	)
	(paper "A4")
	(title_block
		(title "12092022_DA0F0TFB6D0_F0T_FAN_BOARD_MP5048_D_brd_v02_OCP.brd")
		(comment 1 "Grand Teton / footprints 229-234 of 924")
	)
	(layers
		(0 "F.Cu" signal "TOP")
		(4 "In1.Cu" signal "GND")
		(6 "In2.Cu" signal "IN1")
		(8 "In3.Cu" signal "IN2")
		(10 "In4.Cu" signal "GND1")
		(2 "B.Cu" signal "BOTTOM")
		(9 "F.Adhes" user "F.Adhesive")
		(11 "B.Adhes" user "B.Adhesive")
		(13 "F.Paste" user "Package Geometry/Pastemask Top")
		(15 "B.Paste" user "Package Geometry/Pastemask Bottom")
		(5 "F.SilkS" user "Ref Des/Silkscreen Top")
		(7 "B.SilkS" user "Ref Des/Silkscreen Bottom")
		(1 "F.Mask" user "Board Geometry/Soldermask Top")
		(3 "B.Mask" user "Board Geometry/Soldermask Bottom")
		(17 "Dwgs.User" user "User.Drawings")
		(19 "Cmts.User" user "User.Comments")
		(21 "Eco1.User" user "User.Eco1")
		(23 "Eco2.User" user "User.Eco2")
		(25 "Edge.Cuts" user "Board Geometry/Outline")
		(27 "Margin" user)
		(31 "F.CrtYd" user "Package Geometry/Place Bound Top")
		(29 "B.CrtYd" user "Package Geometry/Place Bound Bottom")
		(35 "F.Fab" user "Ref Des/Assembly Top")
		(33 "B.Fab" user "Ref Des/Assembly Bottom")
	)
	(footprint ""
		(layer "F.Cu")
		(at 14.859 -129.794)
		(property "Reference" "R5615"
			(at 0 0 0)
			(layer "F.SilkS")
			(hide yes)
			(effects
				(font
					(size 1.27 1.27)
				)
			)
		)
		(property "Value" ""
			(at 0 0 0)
			(layer "F.Fab")
			(effects
				(font
					(size 1.27 1.27)
				)
			)
		)
		(duplicate_pad_numbers_are_jumpers no)
		(fp_line
			(start -0.7874 -0.4064)
			(end 0.7874 -0.4064)
			(stroke
				(width 0.1524)
				(type default)
			)
			(layer "F.SilkS")
		)
		(fp_line
			(start -0.7874 0.4064)
			(end -0.7874 -0.4064)
			(stroke
				(width 0.1524)
				(type default)
			)
			(layer "F.SilkS")
		)
		(fp_line
			(start 0.7874 -0.4064)
			(end 0.7874 0.4064)
			(stroke
				(width 0.1524)
				(type default)
			)
			(layer "F.SilkS")
		)
		(fp_line
			(start 0.7874 0.4064)
			(end -0.7874 0.4064)
			(stroke
				(width 0.1524)
				(type default)
			)
			(layer "F.SilkS")
		)
		(fp_line
			(start -0.67945 -0.305054)
			(end -0.12065 -0.305054)
			(stroke
				(width 0.1)
				(type default)
			)
			(layer "F.Fab")
		)
		(fp_line
			(start -0.67945 0.3048)
			(end -0.67945 -0.305054)
			(stroke
				(width 0.1)
				(type default)
			)
			(layer "F.Fab")
		)
		(fp_line
			(start -0.12065 -0.305054)
			(end -0.12065 -0.2794)
			(stroke
				(width 0.1)
				(type default)
			)
			(layer "F.Fab")
		)
		(fp_line
			(start -0.12065 -0.2794)
			(end 0.12065 -0.2794)
			(stroke
				(width 0.1)
				(type default)
			)
			(layer "F.Fab")
		)
		(fp_line
			(start -0.12065 0.2794)
			(end -0.12065 0.3048)
			(stroke
				(width 0.1)
				(type default)
			)
			(layer "F.Fab")
		)
		(fp_line
			(start -0.12065 0.3048)
			(end -0.67945 0.3048)
			(stroke
				(width 0.1)
				(type default)
			)
			(layer "F.Fab")
		)
		(fp_line
			(start 0.120396 0.2794)
			(end -0.12065 0.2794)
			(stroke
				(width 0.1)
				(type default)
			)
			(layer "F.Fab")
		)
		(fp_line
			(start 0.120396 0.3048)
			(end 0.120396 0.2794)
			(stroke
				(width 0.1)
				(type default)
			)
			(layer "F.Fab")
		)
		(fp_line
			(start 0.12065 -0.3048)
			(end 0.67945 -0.3048)
			(stroke
				(width 0.1)
				(type default)
			)
			(layer "F.Fab")
		)
		(fp_line
			(start 0.12065 -0.2794)
			(end 0.12065 -0.3048)
			(stroke
				(width 0.1)
				(type default)
			)
			(layer "F.Fab")
		)
		(fp_line
			(start 0.67945 -0.3048)
			(end 0.67945 0.3048)
			(stroke
				(width 0.1)
				(type default)
			)
			(layer "F.Fab")
		)
		(fp_line
			(start 0.67945 0.3048)
			(end 0.120396 0.3048)
			(stroke
				(width 0.1)
				(type default)
			)
			(layer "F.Fab")
		)
		(pad "1" smd rect
			(at -0.40005 0 180)
			(size 0.4572 0.508)
			(layers "F.Cu" "F.Mask" "F.Paste")
			(net "FAN_6_PWM")
		)
		(pad "2" smd rect
			(at 0.40005 0 180)
			(size 0.4572 0.508)
			(layers "F.Cu" "F.Mask" "F.Paste")
			(net "FAN_6_PWM_R1")
		)
	)
	(footprint ""
		(layer "F.Cu")
		(at 27.305 -141.605 -90)
		(property "Reference" "R5278"
			(at 0 0 270)
			(layer "F.SilkS")
			(hide yes)
			(effects
				(font
					(size 1.27 1.27)
				)
			)
		)
		(property "Value" ""
			(at 0 0 270)
			(layer "F.Fab")
			(effects
				(font
					(size 1.27 1.27)
				)
			)
		)
		(duplicate_pad_numbers_are_jumpers no)
		(fp_line
			(start -0.7874 0.4064)
			(end -0.7874 -0.4064)
			(stroke
				(width 0.1524)
				(type default)
			)
			(layer "F.SilkS")
		)
		(fp_line
			(start 0.7874 0.4064)
			(end -0.7874 0.4064)
			(stroke
				(width 0.1524)
				(type default)
			)
			(layer "F.SilkS")
		)
		(fp_line
			(start -0.7874 -0.4064)
			(end 0.7874 -0.4064)
			(stroke
				(width 0.1524)
				(type default)
			)
			(layer "F.SilkS")
		)
		(fp_line
			(start 0.7874 -0.4064)
			(end 0.7874 0.4064)
			(stroke
				(width 0.1524)
				(type default)
			)
			(layer "F.SilkS")
		)
		(fp_line
			(start -0.67945 0.3048)
			(end -0.67945 -0.305054)
			(stroke
				(width 0.1)
				(type default)
			)
			(layer "F.Fab")
		)
		(fp_line
			(start -0.12065 0.3048)
			(end -0.67945 0.3048)
			(stroke
				(width 0.1)
				(type default)
			)
			(layer "F.Fab")
		)
		(fp_line
			(start 0.120396 0.3048)
			(end 0.120396 0.2794)
			(stroke
				(width 0.1)
				(type default)
			)
			(layer "F.Fab")
		)
		(fp_line
			(start 0.67945 0.3048)
			(end 0.120396 0.3048)
			(stroke
				(width 0.1)
				(type default)
			)
			(layer "F.Fab")
		)
		(fp_line
			(start -0.12065 0.2794)
			(end -0.12065 0.3048)
			(stroke
				(width 0.1)
				(type default)
			)
			(layer "F.Fab")
		)
		(fp_line
			(start 0.120396 0.2794)
			(end -0.12065 0.2794)
			(stroke
				(width 0.1)
				(type default)
			)
			(layer "F.Fab")
		)
		(fp_line
			(start -0.12065 -0.2794)
			(end 0.12065 -0.2794)
			(stroke
				(width 0.1)
				(type default)
			)
			(layer "F.Fab")
		)
		(fp_line
			(start 0.12065 -0.2794)
			(end 0.12065 -0.3048)
			(stroke
				(width 0.1)
				(type default)
			)
			(layer "F.Fab")
		)
		(fp_line
			(start 0.12065 -0.3048)
			(end 0.67945 -0.3048)
			(stroke
				(width 0.1)
				(type default)
			)
			(layer "F.Fab")
		)
		(fp_line
			(start 0.67945 -0.3048)
			(end 0.67945 0.3048)
			(stroke
				(width 0.1)
				(type default)
			)
			(layer "F.Fab")
		)
		(fp_line
			(start -0.67945 -0.305054)
			(end -0.12065 -0.305054)
			(stroke
				(width 0.1)
				(type default)
			)
			(layer "F.Fab")
		)
		(fp_line
			(start -0.12065 -0.305054)
			(end -0.12065 -0.2794)
			(stroke
				(width 0.1)
				(type default)
			)
			(layer "F.Fab")
		)
		(pad "1" smd circle
			(at -0.40005 0 270)
			(size 0 0)
			(layers "F.Cu" "F.Mask" "F.Paste")
			(net "SMB_FAN1_R_SCL")
		)
		(pad "2" smd circle
			(at 0.40005 0 270)
			(size 0 0)
			(layers "F.Cu" "F.Mask" "F.Paste")
			(net "P3V3_AUX")
		)
	)
	(footprint ""
		(layer "F.Cu")
		(at 43.561 -137.287 -90)
		(property "Reference" "R5563"
			(at 0 0 270)
			(layer "F.SilkS")
			(hide yes)
			(effects
				(font
					(size 1.27 1.27)
				)
			)
		)
		(property "Value" ""
			(at 0 0 270)
			(layer "F.Fab")
			(effects
				(font
					(size 1.27 1.27)
				)
			)
		)
		(duplicate_pad_numbers_are_jumpers no)
		(fp_line
			(start -0.7874 0.4064)
			(end -0.7874 -0.4064)
			(stroke
				(width 0.1524)
				(type default)
			)
			(layer "F.SilkS")
		)
		(fp_line
			(start 0.7874 0.4064)
			(end -0.7874 0.4064)
			(stroke
				(width 0.1524)
				(type default)
			)
			(layer "F.SilkS")
		)
		(fp_line
			(start -0.7874 -0.4064)
			(end 0.7874 -0.4064)
			(stroke
				(width 0.1524)
				(type default)
			)
			(layer "F.SilkS")
		)
		(fp_line
			(start 0.7874 -0.4064)
			(end 0.7874 0.4064)
			(stroke
				(width 0.1524)
				(type default)
			)
			(layer "F.SilkS")
		)
		(fp_line
			(start -0.67945 0.3048)
			(end -0.67945 -0.305054)
			(stroke
				(width 0.1)
				(type default)
			)
			(layer "F.Fab")
		)
		(fp_line
			(start -0.12065 0.3048)
			(end -0.67945 0.3048)
			(stroke
				(width 0.1)
				(type default)
			)
			(layer "F.Fab")
		)
		(fp_line
			(start 0.120396 0.3048)
			(end 0.120396 0.2794)
			(stroke
				(width 0.1)
				(type default)
			)
			(layer "F.Fab")
		)
		(fp_line
			(start 0.67945 0.3048)
			(end 0.120396 0.3048)
			(stroke
				(width 0.1)
				(type default)
			)
			(layer "F.Fab")
		)
		(fp_line
			(start -0.12065 0.2794)
			(end -0.12065 0.3048)
			(stroke
				(width 0.1)
				(type default)
			)
			(layer "F.Fab")
		)
		(fp_line
			(start 0.120396 0.2794)
			(end -0.12065 0.2794)
			(stroke
				(width 0.1)
				(type default)
			)
			(layer "F.Fab")
		)
		(fp_line
			(start -0.12065 -0.2794)
			(end 0.12065 -0.2794)
			(stroke
				(width 0.1)
				(type default)
			)
			(layer "F.Fab")
		)
		(fp_line
			(start 0.12065 -0.2794)
			(end 0.12065 -0.3048)
			(stroke
				(width 0.1)
				(type default)
			)
			(layer "F.Fab")
		)
		(fp_line
			(start 0.12065 -0.3048)
			(end 0.67945 -0.3048)
			(stroke
				(width 0.1)
				(type default)
			)
			(layer "F.Fab")
		)
		(fp_line
			(start 0.67945 -0.3048)
			(end 0.67945 0.3048)
			(stroke
				(width 0.1)
				(type default)
			)
			(layer "F.Fab")
		)
		(fp_line
			(start -0.67945 -0.305054)
			(end -0.12065 -0.305054)
			(stroke
				(width 0.1)
				(type default)
			)
			(layer "F.Fab")
		)
		(fp_line
			(start -0.12065 -0.305054)
			(end -0.12065 -0.2794)
			(stroke
				(width 0.1)
				(type default)
			)
			(layer "F.Fab")
		)
		(pad "1" smd circle
			(at -0.40005 0 270)
			(size 0 0)
			(layers "F.Cu" "F.Mask" "F.Paste")
			(net "GND")
		)
		(pad "2" smd circle
			(at 0.40005 0 270)
			(size 0 0)
			(layers "F.Cu" "F.Mask" "F.Paste")
			(net "U403_ADD1")
		)
	)
	(footprint ""
		(layer "F.Cu")
		(at 23.114 -160.02 90)
		(property "Reference" "R4884"
			(at 0 0 90)
			(layer "F.SilkS")
			(hide yes)
			(effects
				(font
					(size 1.27 1.27)
				)
			)
		)
		(property "Value" ""
			(at 0 0 90)
			(layer "F.Fab")
			(effects
				(font
					(size 1.27 1.27)
				)
			)
		)
		(duplicate_pad_numbers_are_jumpers no)
		(fp_line
			(start 0.7874 -0.4064)
			(end 0.7874 0.4064)
			(stroke
				(width 0.1524)
				(type default)
			)
			(layer "F.SilkS")
		)
		(fp_line
			(start -0.7874 -0.4064)
			(end 0.7874 -0.4064)
			(stroke
				(width 0.1524)
				(type default)
			)
			(layer "F.SilkS")
		)
		(fp_line
			(start 0.7874 0.4064)
			(end -0.7874 0.4064)
			(stroke
				(width 0.1524)
				(type default)
			)
			(layer "F.SilkS")
		)
		(fp_line
			(start -0.7874 0.4064)
			(end -0.7874 -0.4064)
			(stroke
				(width 0.1524)
				(type default)
			)
			(layer "F.SilkS")
		)
		(fp_line
			(start -0.12065 -0.305054)
			(end -0.12065 -0.2794)
			(stroke
				(width 0.1)
				(type default)
			)
			(layer "F.Fab")
		)
		(fp_line
			(start -0.67945 -0.305054)
			(end -0.12065 -0.305054)
			(stroke
				(width 0.1)
				(type default)
			)
			(layer "F.Fab")
		)
		(fp_line
			(start 0.67945 -0.3048)
			(end 0.67945 0.3048)
			(stroke
				(width 0.1)
				(type default)
			)
			(layer "F.Fab")
		)
		(fp_line
			(start 0.12065 -0.3048)
			(end 0.67945 -0.3048)
			(stroke
				(width 0.1)
				(type default)
			)
			(layer "F.Fab")
		)
		(fp_line
			(start 0.12065 -0.2794)
			(end 0.12065 -0.3048)
			(stroke
				(width 0.1)
				(type default)
			)
			(layer "F.Fab")
		)
		(fp_line
			(start -0.12065 -0.2794)
			(end 0.12065 -0.2794)
			(stroke
				(width 0.1)
				(type default)
			)
			(layer "F.Fab")
		)
		(fp_line
			(start 0.120396 0.2794)
			(end -0.12065 0.2794)
			(stroke
				(width 0.1)
				(type default)
			)
			(layer "F.Fab")
		)
		(fp_line
			(start -0.12065 0.2794)
			(end -0.12065 0.3048)
			(stroke
				(width 0.1)
				(type default)
			)
			(layer "F.Fab")
		)
		(fp_line
			(start 0.67945 0.3048)
			(end 0.120396 0.3048)
			(stroke
				(width 0.1)
				(type default)
			)
			(layer "F.Fab")
		)
		(fp_line
			(start 0.120396 0.3048)
			(end 0.120396 0.2794)
			(stroke
				(width 0.1)
				(type default)
			)
			(layer "F.Fab")
		)
		(fp_line
			(start -0.12065 0.3048)
			(end -0.67945 0.3048)
			(stroke
				(width 0.1)
				(type default)
			)
			(layer "F.Fab")
		)
		(fp_line
			(start -0.67945 0.3048)
			(end -0.67945 -0.305054)
			(stroke
				(width 0.1)
				(type default)
			)
			(layer "F.Fab")
		)
		(pad "1" smd circle
			(at -0.40005 0 90)
			(size 0 0)
			(layers "F.Cu" "F.Mask" "F.Paste")
			(net "SMB_FAN7_R_SDA")
		)
		(pad "2" smd circle
			(at 0.40005 0 90)
			(size 0 0)
			(layers "F.Cu" "F.Mask" "F.Paste")
			(net "SMB_FAN7_SDA")
		)
	)
	(footprint ""
		(layer "F.Cu")
		(at 43.561 -169.799)
		(property "Reference" "R5094"
			(at 0 0 0)
			(layer "F.SilkS")
			(hide yes)
			(effects
				(font
					(size 1.27 1.27)
				)
			)
		)
		(property "Value" ""
			(at 0 0 0)
			(layer "F.Fab")
			(effects
				(font
					(size 1.27 1.27)
				)
			)
		)
		(duplicate_pad_numbers_are_jumpers no)
		(fp_line
			(start -0.7874 -0.4064)
			(end 0.7874 -0.4064)
			(stroke
				(width 0.1524)
				(type default)
			)
			(layer "F.SilkS")
		)
		(fp_line
			(start -0.7874 0.4064)
			(end -0.7874 -0.4064)
			(stroke
				(width 0.1524)
				(type default)
			)
			(layer "F.SilkS")
		)
		(fp_line
			(start 0.7874 -0.4064)
			(end 0.7874 0.4064)
			(stroke
				(width 0.1524)
				(type default)
			)
			(layer "F.SilkS")
		)
		(fp_line
			(start 0.7874 0.4064)
			(end -0.7874 0.4064)
			(stroke
				(width 0.1524)
				(type default)
			)
			(layer "F.SilkS")
		)
		(fp_line
			(start -0.67945 -0.305054)
			(end -0.12065 -0.305054)
			(stroke
				(width 0.1)
				(type default)
			)
			(layer "F.Fab")
		)
		(fp_line
			(start -0.67945 0.3048)
			(end -0.67945 -0.305054)
			(stroke
				(width 0.1)
				(type default)
			)
			(layer "F.Fab")
		)
		(fp_line
			(start -0.12065 -0.305054)
			(end -0.12065 -0.2794)
			(stroke
				(width 0.1)
				(type default)
			)
			(layer "F.Fab")
		)
		(fp_line
			(start -0.12065 -0.2794)
			(end 0.12065 -0.2794)
			(stroke
				(width 0.1)
				(type default)
			)
			(layer "F.Fab")
		)
		(fp_line
			(start -0.12065 0.2794)
			(end -0.12065 0.3048)
			(stroke
				(width 0.1)
				(type default)
			)
			(layer "F.Fab")
		)
		(fp_line
			(start -0.12065 0.3048)
			(end -0.67945 0.3048)
			(stroke
				(width 0.1)
				(type default)
			)
			(layer "F.Fab")
		)
		(fp_line
			(start 0.120396 0.2794)
			(end -0.12065 0.2794)
			(stroke
				(width 0.1)
				(type default)
			)
			(layer "F.Fab")
		)
		(fp_line
			(start 0.120396 0.3048)
			(end 0.120396 0.2794)
			(stroke
				(width 0.1)
				(type default)
			)
			(layer "F.Fab")
		)
		(fp_line
			(start 0.12065 -0.3048)
			(end 0.67945 -0.3048)
			(stroke
				(width 0.1)
				(type default)
			)
			(layer "F.Fab")
		)
		(fp_line
			(start 0.12065 -0.2794)
			(end 0.12065 -0.3048)
			(stroke
				(width 0.1)
				(type default)
			)
			(layer "F.Fab")
		)
		(fp_line
			(start 0.67945 -0.3048)
			(end 0.67945 0.3048)
			(stroke
				(width 0.1)
				(type default)
			)
			(layer "F.Fab")
		)
		(fp_line
			(start 0.67945 0.3048)
			(end 0.120396 0.3048)
			(stroke
				(width 0.1)
				(type default)
			)
			(layer "F.Fab")
		)
		(pad "1" smd circle
			(at -0.40005 0)
			(size 0 0)
			(layers "F.Cu" "F.Mask" "F.Paste")
			(net "FAN_0_OK_LED")
		)
		(pad "2" smd circle
			(at 0.40005 0)
			(size 0 0)
			(layers "F.Cu" "F.Mask" "F.Paste")
			(net "FAN_0_OK_R_LED")
		)
	)
	(footprint ""
		(layer "F.Cu")
		(at 41.441116 -39.403274)
		(property "Reference" "PC35"
			(at 2.373884 6.028944 0)
			(unlocked yes)
			(layer "F.SilkS")
			(effects
				(font
					(size 0.7874 0.5842)
					(thickness 0.1524)
				)
				(justify left)
			)
		)
		(property "Value" ""
			(at 0 0 0)
			(layer "F.Fab")
			(effects
				(font
					(size 1.27 1.27)
				)
			)
		)
		(duplicate_pad_numbers_are_jumpers no)
		(fp_line
			(start -5.249926 -3.979926)
			(end -5.249926 -1.2446)
			(stroke
				(width 0.1524)
				(type default)
			)
			(layer "F.SilkS")
		)
		(fp_line
			(start -5.249926 1.2446)
			(end -5.249926 3.979926)
			(stroke
				(width 0.1524)
				(type default)
			)
			(layer "F.SilkS")
		)
		(fp_line
			(start -5.249926 3.979926)
			(end -3.979926 5.249926)
			(stroke
				(width 0.1524)
				(type default)
			)
			(layer "F.SilkS")
		)
		(fp_line
			(start -3.979926 -5.249926)
			(end -5.249926 -3.979926)
			(stroke
				(width 0.1524)
				(type default)
			)
			(layer "F.SilkS")
		)
		(fp_line
			(start -3.979926 5.249926)
			(end 5.249926 5.249926)
			(stroke
				(width 0.1524)
				(type default)
			)
			(layer "F.SilkS")
		)
		(fp_line
			(start 5.249926 -5.249926)
			(end -3.979926 -5.249926)
			(stroke
				(width 0.1524)
				(type default)
			)
			(layer "F.SilkS")
		)
		(fp_line
			(start 5.249926 -1.2446)
			(end 5.249926 -5.249926)
			(stroke
				(width 0.1524)
				(type default)
			)
			(layer "F.SilkS")
		)
		(fp_line
			(start 5.249926 5.249926)
			(end 5.249926 1.2446)
			(stroke
				(width 0.1524)
				(type default)
			)
			(layer "F.SilkS")
		)
		(fp_line
			(start -5.249926 -5.249926)
			(end -5.249926 5.249926)
			(stroke
				(width 0.1)
				(type default)
			)
			(layer "F.Fab")
		)
		(fp_line
			(start -5.249926 5.249926)
			(end 5.249926 5.249926)
			(stroke
				(width 0.1)
				(type default)
			)
			(layer "F.Fab")
		)
		(fp_line
			(start 5.249926 -5.249926)
			(end -5.249926 -5.249926)
			(stroke
				(width 0.1)
				(type default)
			)
			(layer "F.Fab")
		)
		(fp_line
			(start 5.249926 5.249926)
			(end 5.249926 -5.249926)
			(stroke
				(width 0.1)
				(type default)
			)
			(layer "F.Fab")
		)
		(pad "1" smd rect
			(at -4.45008 0 90)
			(size 2.2098 4.4196)
			(layers "F.Cu" "F.Mask" "F.Paste")
			(net "P52V_FAN_3")
		)
		(pad "2" smd rect
			(at 4.45008 0 90)
			(size 2.2098 4.4196)
			(layers "F.Cu" "F.Mask" "F.Paste")
			(net "GND")
		)
	)
)
